(kicad_pcb
	(version 20241229)
	(generator "pcbnew")
	(generator_version "9.0")
	(general
		(thickness 1.62)
		(legacy_teardrops no)
	)
	(paper "A3")
	(title_block
		(title "COM Express 7 Baseboard")
		(date "2025-02-04")
		(rev "1.1.2")
		(company "Antmicro Ltd")
		(comment 1 "www.antmicro.com")
		(comment 9 "footprint 489 of 802 (J12), pads 125-164 of 450")
	)
	(layers
		(0 "F.Cu" signal)
		(4 "In1.Cu" signal)
		(6 "In2.Cu" signal)
		(8 "In3.Cu" signal)
		(10 "In4.Cu" signal)
		(12 "In5.Cu" signal)
		(14 "In6.Cu" signal)
		(2 "B.Cu" signal)
		(9 "F.Adhes" user "F.Adhesive")
		(11 "B.Adhes" user "B.Adhesive")
		(13 "F.Paste" user)
		(15 "B.Paste" user)
		(5 "F.SilkS" user "F.Silkscreen")
		(7 "B.SilkS" user "B.Silkscreen")
		(1 "F.Mask" user)
		(3 "B.Mask" user)
		(17 "Dwgs.User" user "User.Drawings")
		(19 "Cmts.User" user "User.Comments")
		(21 "Eco1.User" user "User.Eco1")
		(23 "Eco2.User" user "User.Eco2")
		(25 "Edge.Cuts" user)
		(27 "Margin" user)
		(31 "F.CrtYd" user "F.Courtyard")
		(29 "B.CrtYd" user "B.Courtyard")
		(35 "F.Fab" user)
		(33 "B.Fab" user)
	)
	(footprint "antmicro-footprints:EPT_401-51501-51"
		(layer "F.Cu")
		(at 203.275 159.81)
		(property "Reference" "J12"
			(at 30.975 -10.45 0)
			(layer "F.SilkS")
			(effects
				(font
					(size 0.7 0.7)
					(thickness 0.15)
				)
				(justify right top)
			)
		)
		(property "Value" "Plug_Bus_CE7_EPT_401-51501-51"
			(at -3.225 52.665 0)
			(layer "F.Fab")
			(hide yes)
			(effects
				(font
					(size 0.7 0.7)
					(thickness 0.15)
				)
				(justify left top)
			)
		)
		(property "Datasheet" "https://www.farnell.com/datasheets/1905093.pdf"
			(at 0 0 0)
			(layer "F.Fab")
			(hide yes)
			(effects
				(font
					(size 1.27 1.27)
					(thickness 0.15)
				)
			)
		)
		(property "Author" "Antmicro"
			(at 406.55 319.62 0)
			(layer "F.Fab")
			(hide yes)
			(effects
				(font
					(size 1 1)
					(thickness 0.15)
				)
			)
		)
		(property "License" "Apache-2.0"
			(at 406.55 319.62 0)
			(layer "F.Fab")
			(hide yes)
			(effects
				(font
					(size 1 1)
					(thickness 0.15)
				)
			)
		)
		(property "MPN" "401-51501-51"
			(at 406.55 319.62 0)
			(layer "F.Fab")
			(hide yes)
			(effects
				(font
					(size 1 1)
					(thickness 0.15)
				)
			)
		)
		(property "Manufacturer" "ept"
			(at 406.55 319.62 0)
			(layer "F.Fab")
			(hide yes)
			(effects
				(font
					(size 1 1)
					(thickness 0.15)
				)
			)
		)
		(sheetname "Com Express 7 Interfaces")
		(sheetfile "com_express_7_interfaces.kicad_sch")
		(attr smd)
		(pad "B10" smd rect
			(at -22.75 3.325)
			(size 0.3 1.75)
			(layers "F.Cu" "F.Mask" "F.Paste")
			(net 355 "Net-(J12D-LPC_CLK{slash}ESPI_CK)")
			(pinfunction "LPC_CLK/ESPI_CK")
			(pintype "output")
			(teardrops
				(best_length_ratio 0.2)
				(max_length 1)
				(best_width_ratio 0.9)
				(max_width 2)
				(curved_edges yes)
				(filter_ratio 0.9)
				(enabled yes)
				(allow_two_segments yes)
				(prefer_zone_connections yes)
			)
		)
		(pad "B11" smd rect
			(at -22.25 3.325)
			(size 0.3 1.75)
			(layers "F.Cu" "F.Mask" "F.Paste")
			(net 1 "GND")
			(pinfunction "GND(FIXED)")
			(pintype "passive")
			(teardrops
				(best_length_ratio 0.2)
				(max_length 1)
				(best_width_ratio 0.9)
				(max_width 2)
				(curved_edges yes)
				(filter_ratio 0.9)
				(enabled yes)
				(allow_two_segments yes)
				(prefer_zone_connections yes)
			)
		)
		(pad "B12" smd rect
			(at -21.75 3.325)
			(size 0.3 1.75)
			(layers "F.Cu" "F.Mask" "F.Paste")
			(net 356 "/Com Express 7 MGMT/~{CW_PWRBTN}")
			(pinfunction "~{PWRBTN}")
			(pintype "input")
			(teardrops
				(best_length_ratio 0.2)
				(max_length 1)
				(best_width_ratio 0.9)
				(max_width 2)
				(curved_edges yes)
				(filter_ratio 0.9)
				(enabled yes)
				(allow_two_segments yes)
				(prefer_zone_connections yes)
			)
		)
		(pad "B13" smd rect
			(at -21.25 3.325)
			(size 0.3 1.75)
			(layers "F.Cu" "F.Mask" "F.Paste")
			(net 357 "/Com Express 7 MGMT/SMBus.SCL")
			(pinfunction "SMB_CK")
			(pintype "open_collector")
			(teardrops
				(best_length_ratio 0.2)
				(max_length 1)
				(best_width_ratio 0.9)
				(max_width 2)
				(curved_edges yes)
				(filter_ratio 0.9)
				(enabled yes)
				(allow_two_segments yes)
				(prefer_zone_connections yes)
			)
		)
		(pad "B14" smd rect
			(at -20.75 3.325)
			(size 0.3 1.75)
			(layers "F.Cu" "F.Mask" "F.Paste")
			(net 358 "/Com Express 7 MGMT/SMBus.SDA")
			(pinfunction "SMB_DAT")
			(pintype "open_collector")
			(teardrops
				(best_length_ratio 0.2)
				(max_length 1)
				(best_width_ratio 0.9)
				(max_width 2)
				(curved_edges yes)
				(filter_ratio 0.9)
				(enabled yes)
				(allow_two_segments yes)
				(prefer_zone_connections yes)
			)
		)
		(pad "B15" smd rect
			(at -20.25 3.325)
			(size 0.3 1.75)
			(layers "F.Cu" "F.Mask" "F.Paste")
			(net 359 "/Com Express 7 MGMT/SMBus.~{INT}")
			(pinfunction "~{SMB_ALERT}")
			(pintype "input")
			(teardrops
				(best_length_ratio 0.2)
				(max_length 1)
				(best_width_ratio 0.9)
				(max_width 2)
				(curved_edges yes)
				(filter_ratio 0.9)
				(enabled yes)
				(allow_two_segments yes)
				(prefer_zone_connections yes)
			)
		)
		(pad "B16" smd rect
			(at -19.75 3.325)
			(size 0.3 1.75)
			(layers "F.Cu" "F.Mask" "F.Paste")
			(net 360 "unconnected-(J12F-SATA1_TX+-PadB16)")
			(pinfunction "SATA1_TX+")
			(pintype "output+no_connect")
			(teardrops
				(best_length_ratio 0.2)
				(max_length 1)
				(best_width_ratio 0.9)
				(max_width 2)
				(curved_edges yes)
				(filter_ratio 0.9)
				(enabled yes)
				(allow_two_segments yes)
				(prefer_zone_connections yes)
			)
		)
		(pad "B17" smd rect
			(at -19.25 3.325)
			(size 0.3 1.75)
			(layers "F.Cu" "F.Mask" "F.Paste")
			(net 361 "unconnected-(J12F-SATA1_TX--PadB17)")
			(pinfunction "SATA1_TX-")
			(pintype "output+no_connect")
			(teardrops
				(best_length_ratio 0.2)
				(max_length 1)
				(best_width_ratio 0.9)
				(max_width 2)
				(curved_edges yes)
				(filter_ratio 0.9)
				(enabled yes)
				(allow_two_segments yes)
				(prefer_zone_connections yes)
			)
		)
		(pad "B18" smd rect
			(at -18.75 3.325)
			(size 0.3 1.75)
			(layers "F.Cu" "F.Mask" "F.Paste")
			(net 362 "Net-(J12D-~{SUS_STAT}{slash}~{ESPI_RESET})")
			(pinfunction "~{SUS_STAT}/~{ESPI_RESET}")
			(pintype "output")
			(teardrops
				(best_length_ratio 0.2)
				(max_length 1)
				(best_width_ratio 0.9)
				(max_width 2)
				(curved_edges yes)
				(filter_ratio 0.9)
				(enabled yes)
				(allow_two_segments yes)
				(prefer_zone_connections yes)
			)
		)
		(pad "B19" smd rect
			(at -18.25 3.325)
			(size 0.3 1.75)
			(layers "F.Cu" "F.Mask" "F.Paste")
			(net 363 "unconnected-(J12F-SATA1_RX+-PadB19)")
			(pinfunction "SATA1_RX+")
			(pintype "input+no_connect")
			(teardrops
				(best_length_ratio 0.2)
				(max_length 1)
				(best_width_ratio 0.9)
				(max_width 2)
				(curved_edges yes)
				(filter_ratio 0.9)
				(enabled yes)
				(allow_two_segments yes)
				(prefer_zone_connections yes)
			)
		)
		(pad "B20" smd rect
			(at -17.75 3.325)
			(size 0.3 1.75)
			(layers "F.Cu" "F.Mask" "F.Paste")
			(net 364 "unconnected-(J12F-SATA1_RX--PadB20)")
			(pinfunction "SATA1_RX-")
			(pintype "input+no_connect")
			(teardrops
				(best_length_ratio 0.2)
				(max_length 1)
				(best_width_ratio 0.9)
				(max_width 2)
				(curved_edges yes)
				(filter_ratio 0.9)
				(enabled yes)
				(allow_two_segments yes)
				(prefer_zone_connections yes)
			)
		)
		(pad "B21" smd rect
			(at -17.25 3.325)
			(size 0.3 1.75)
			(layers "F.Cu" "F.Mask" "F.Paste")
			(net 1 "GND")
			(pinfunction "GND(FIXED)")
			(pintype "passive")
			(teardrops
				(best_length_ratio 0.2)
				(max_length 1)
				(best_width_ratio 0.9)
				(max_width 2)
				(curved_edges yes)
				(filter_ratio 0.9)
				(enabled yes)
				(allow_two_segments yes)
				(prefer_zone_connections yes)
			)
		)
		(pad "B22" smd rect
			(at -16.75 3.325)
			(size 0.3 1.75)
			(layers "F.Cu" "F.Mask" "F.Paste")
			(net 239 "/Com Express 7 Interfaces/PCIe_{B2Bx4}.RX3+")
			(pinfunction "PCIE_RX15+")
			(pintype "input")
			(teardrops
				(best_length_ratio 0.2)
				(max_length 1)
				(best_width_ratio 0.9)
				(max_width 2)
				(curved_edges yes)
				(filter_ratio 0.9)
				(enabled yes)
				(allow_two_segments yes)
				(prefer_zone_connections yes)
			)
		)
		(pad "B23" smd rect
			(at -16.25 3.325)
			(size 0.3 1.75)
			(layers "F.Cu" "F.Mask" "F.Paste")
			(net 237 "/Com Express 7 Interfaces/PCIe_{B2Bx4}.RX3-")
			(pinfunction "PCIE_RX15-")
			(pintype "input")
			(teardrops
				(best_length_ratio 0.2)
				(max_length 1)
				(best_width_ratio 0.9)
				(max_width 2)
				(curved_edges yes)
				(filter_ratio 0.9)
				(enabled yes)
				(allow_two_segments yes)
				(prefer_zone_connections yes)
			)
		)
		(pad "B24" smd rect
			(at -15.75 3.325)
			(size 0.3 1.75)
			(layers "F.Cu" "F.Mask" "F.Paste")
			(net 365 "/Com Express 7 MGMT/PWR_OK")
			(pinfunction "PWR_OK")
			(pintype "input")
			(teardrops
				(best_length_ratio 0.2)
				(max_length 1)
				(best_width_ratio 0.9)
				(max_width 2)
				(curved_edges yes)
				(filter_ratio 0.9)
				(enabled yes)
				(allow_two_segments yes)
				(prefer_zone_connections yes)
			)
		)
		(pad "B25" smd rect
			(at -15.25 3.325)
			(size 0.3 1.75)
			(layers "F.Cu" "F.Mask" "F.Paste")
			(net 244 "/Com Express 7 Interfaces/PCIe_{B2Bx4}.RX2+")
			(pinfunction "PCIE_RX14+")
			(pintype "input")
			(teardrops
				(best_length_ratio 0.2)
				(max_length 1)
				(best_width_ratio 0.9)
				(max_width 2)
				(curved_edges yes)
				(filter_ratio 0.9)
				(enabled yes)
				(allow_two_segments yes)
				(prefer_zone_connections yes)
			)
		)
		(pad "B26" smd rect
			(at -14.75 3.325)
			(size 0.3 1.75)
			(layers "F.Cu" "F.Mask" "F.Paste")
			(net 243 "/Com Express 7 Interfaces/PCIe_{B2Bx4}.RX2-")
			(pinfunction "PCIE_RX14-")
			(pintype "input")
			(teardrops
				(best_length_ratio 0.2)
				(max_length 1)
				(best_width_ratio 0.9)
				(max_width 2)
				(curved_edges yes)
				(filter_ratio 0.9)
				(enabled yes)
				(allow_two_segments yes)
				(prefer_zone_connections yes)
			)
		)
		(pad "B27" smd rect
			(at -14.25 3.325)
			(size 0.3 1.75)
			(layers "F.Cu" "F.Mask" "F.Paste")
			(net 366 "Net-(J12D-WDT)")
			(pinfunction "WDT")
			(pintype "output")
			(teardrops
				(best_length_ratio 0.2)
				(max_length 1)
				(best_width_ratio 0.9)
				(max_width 2)
				(curved_edges yes)
				(filter_ratio 0.9)
				(enabled yes)
				(allow_two_segments yes)
				(prefer_zone_connections yes)
			)
		)
		(pad "B28" smd rect
			(at -13.75 3.325)
			(size 0.3 1.75)
			(layers "F.Cu" "F.Mask" "F.Paste")
			(net 367 "unconnected-(J12H-RSVD-PadB28)")
			(pinfunction "RSVD")
			(pintype "no_connect")
			(teardrops
				(best_length_ratio 0.2)
				(max_length 1)
				(best_width_ratio 0.9)
				(max_width 2)
				(curved_edges yes)
				(filter_ratio 0.9)
				(enabled yes)
				(allow_two_segments yes)
				(prefer_zone_connections yes)
			)
		)
		(pad "B29" smd rect
			(at -13.25 3.325)
			(size 0.3 1.75)
			(layers "F.Cu" "F.Mask" "F.Paste")
			(net 368 "unconnected-(J12H-RSVD-PadB29)")
			(pinfunction "RSVD")
			(pintype "no_connect")
			(teardrops
				(best_length_ratio 0.2)
				(max_length 1)
				(best_width_ratio 0.9)
				(max_width 2)
				(curved_edges yes)
				(filter_ratio 0.9)
				(enabled yes)
				(allow_two_segments yes)
				(prefer_zone_connections yes)
			)
		)
		(pad "B30" smd rect
			(at -12.75 3.325)
			(size 0.3 1.75)
			(layers "F.Cu" "F.Mask" "F.Paste")
			(net 369 "unconnected-(J12H-RSVD-PadB30)")
			(pinfunction "RSVD")
			(pintype "no_connect")
			(teardrops
				(best_length_ratio 0.2)
				(max_length 1)
				(best_width_ratio 0.9)
				(max_width 2)
				(curved_edges yes)
				(filter_ratio 0.9)
				(enabled yes)
				(allow_two_segments yes)
				(prefer_zone_connections yes)
			)
		)
		(pad "B31" smd rect
			(at -12.25 3.325)
			(size 0.3 1.75)
			(layers "F.Cu" "F.Mask" "F.Paste")
			(net 1 "GND")
			(pinfunction "GND(FIXED)")
			(pintype "passive")
			(teardrops
				(best_length_ratio 0.2)
				(max_length 1)
				(best_width_ratio 0.9)
				(max_width 2)
				(curved_edges yes)
				(filter_ratio 0.9)
				(enabled yes)
				(allow_two_segments yes)
				(prefer_zone_connections yes)
			)
		)
		(pad "B32" smd rect
			(at -11.75 3.325)
			(size 0.3 1.75)
			(layers "F.Cu" "F.Mask" "F.Paste")
			(net 370 "Net-(J12D-SPKR)")
			(pinfunction "SPKR")
			(pintype "output")
			(teardrops
				(best_length_ratio 0.2)
				(max_length 1)
				(best_width_ratio 0.9)
				(max_width 2)
				(curved_edges yes)
				(filter_ratio 0.9)
				(enabled yes)
				(allow_two_segments yes)
				(prefer_zone_connections yes)
			)
		)
		(pad "B33" smd rect
			(at -11.25 3.325)
			(size 0.3 1.75)
			(layers "F.Cu" "F.Mask" "F.Paste")
			(net 371 "/Com Express 7 MGMT/I2C.SCL")
			(pinfunction "I2C_CK")
			(pintype "open_collector")
			(teardrops
				(best_length_ratio 0.2)
				(max_length 1)
				(best_width_ratio 0.9)
				(max_width 2)
				(curved_edges yes)
				(filter_ratio 0.9)
				(enabled yes)
				(allow_two_segments yes)
				(prefer_zone_connections yes)
			)
		)
		(pad "B34" smd rect
			(at -10.75 3.325)
			(size 0.3 1.75)
			(layers "F.Cu" "F.Mask" "F.Paste")
			(net 372 "/Com Express 7 MGMT/I2C.SDA")
			(pinfunction "I2C_DAT")
			(pintype "open_collector")
			(teardrops
				(best_length_ratio 0.2)
				(max_length 1)
				(best_width_ratio 0.9)
				(max_width 2)
				(curved_edges yes)
				(filter_ratio 0.9)
				(enabled yes)
				(allow_two_segments yes)
				(prefer_zone_connections yes)
			)
		)
		(pad "B35" smd rect
			(at -10.25 3.325)
			(size 0.3 1.75)
			(layers "F.Cu" "F.Mask" "F.Paste")
			(net 373 "Net-(J12D-~{THRM})")
			(pinfunction "~{THRM}")
			(pintype "input")
			(teardrops
				(best_length_ratio 0.2)
				(max_length 1)
				(best_width_ratio 0.9)
				(max_width 2)
				(curved_edges yes)
				(filter_ratio 0.9)
				(enabled yes)
				(allow_two_segments yes)
				(prefer_zone_connections yes)
			)
		)
		(pad "B36" smd rect
			(at -9.75 3.325)
			(size 0.3 1.75)
			(layers "F.Cu" "F.Mask" "F.Paste")
			(net 254 "/Com Express 7 Interfaces/PCIe_{B2Bx4}.RX1+")
			(pinfunction "PCIE_RX13+")
			(pintype "input")
			(teardrops
				(best_length_ratio 0.2)
				(max_length 1)
				(best_width_ratio 0.9)
				(max_width 2)
				(curved_edges yes)
				(filter_ratio 0.9)
				(enabled yes)
				(allow_two_segments yes)
				(prefer_zone_connections yes)
			)
		)
		(pad "B37" smd rect
			(at -9.25 3.325)
			(size 0.3 1.75)
			(layers "F.Cu" "F.Mask" "F.Paste")
			(net 252 "/Com Express 7 Interfaces/PCIe_{B2Bx4}.RX1-")
			(pinfunction "PCIE_RX13-")
			(pintype "input")
			(teardrops
				(best_length_ratio 0.2)
				(max_length 1)
				(best_width_ratio 0.9)
				(max_width 2)
				(curved_edges yes)
				(filter_ratio 0.9)
				(enabled yes)
				(allow_two_segments yes)
				(prefer_zone_connections yes)
			)
		)
		(pad "B38" smd rect
			(at -8.75 3.325)
			(size 0.3 1.75)
			(layers "F.Cu" "F.Mask" "F.Paste")
			(net 1 "GND")
			(pinfunction "GND")
			(pintype "passive")
			(teardrops
				(best_length_ratio 0.2)
				(max_length 1)
				(best_width_ratio 0.9)
				(max_width 2)
				(curved_edges yes)
				(filter_ratio 0.9)
				(enabled yes)
				(allow_two_segments yes)
				(prefer_zone_connections yes)
			)
		)
		(pad "B39" smd rect
			(at -8.25 3.325)
			(size 0.3 1.75)
			(layers "F.Cu" "F.Mask" "F.Paste")
			(net 264 "/Com Express 7 Interfaces/PCIe_{B2Bx4}.RX0+")
			(pinfunction "PCIE_RX12+")
			(pintype "input")
			(teardrops
				(best_length_ratio 0.2)
				(max_length 1)
				(best_width_ratio 0.9)
				(max_width 2)
				(curved_edges yes)
				(filter_ratio 0.9)
				(enabled yes)
				(allow_two_segments yes)
				(prefer_zone_connections yes)
			)
		)
		(pad "B40" smd rect
			(at -7.75 3.325)
			(size 0.3 1.75)
			(layers "F.Cu" "F.Mask" "F.Paste")
			(net 262 "/Com Express 7 Interfaces/PCIe_{B2Bx4}.RX0-")
			(pinfunction "PCIE_RX12-")
			(pintype "input")
			(teardrops
				(best_length_ratio 0.2)
				(max_length 1)
				(best_width_ratio 0.9)
				(max_width 2)
				(curved_edges yes)
				(filter_ratio 0.9)
				(enabled yes)
				(allow_two_segments yes)
				(prefer_zone_connections yes)
			)
		)
		(pad "B41" smd rect
			(at -7.25 3.325)
			(size 0.3 1.75)
			(layers "F.Cu" "F.Mask" "F.Paste")
			(net 1 "GND")
			(pinfunction "GND(FIXED)")
			(pintype "passive")
			(teardrops
				(best_length_ratio 0.2)
				(max_length 1)
				(best_width_ratio 0.9)
				(max_width 2)
				(curved_edges yes)
				(filter_ratio 0.9)
				(enabled yes)
				(allow_two_segments yes)
				(prefer_zone_connections yes)
			)
		)
		(pad "B42" smd rect
			(at -6.75 3.325)
			(size 0.3 1.75)
			(layers "F.Cu" "F.Mask" "F.Paste")
			(net 374 "/2xUSB3.0+RJ45/USB_2.D-")
			(pinfunction "USB3-")
			(pintype "bidirectional")
			(teardrops
				(best_length_ratio 0.2)
				(max_length 1)
				(best_width_ratio 0.9)
				(max_width 2)
				(curved_edges yes)
				(filter_ratio 0.9)
				(enabled yes)
				(allow_two_segments yes)
				(prefer_zone_connections yes)
			)
		)
		(pad "B43" smd rect
			(at -6.25 3.325)
			(size 0.3 1.75)
			(layers "F.Cu" "F.Mask" "F.Paste")
			(net 375 "/2xUSB3.0+RJ45/USB_2.D+")
			(pinfunction "USB3+")
			(pintype "bidirectional")
			(teardrops
				(best_length_ratio 0.2)
				(max_length 1)
				(best_width_ratio 0.9)
				(max_width 2)
				(curved_edges yes)
				(filter_ratio 0.9)
				(enabled yes)
				(allow_two_segments yes)
				(prefer_zone_connections yes)
			)
		)
		(pad "B44" smd rect
			(at -5.75 3.325)
			(size 0.3 1.75)
			(layers "F.Cu" "F.Mask" "F.Paste")
			(net 376 "unconnected-(J12G-~{USB_0_1_OC}-PadB44)")
			(pinfunction "~{USB_0_1_OC}")
			(pintype "input+no_connect")
			(teardrops
				(best_length_ratio 0.2)
				(max_length 1)
				(best_width_ratio 0.9)
				(max_width 2)
				(curved_edges yes)
				(filter_ratio 0.9)
				(enabled yes)
				(allow_two_segments yes)
				(prefer_zone_connections yes)
			)
		)
		(pad "B45" smd rect
			(at -5.25 3.325)
			(size 0.3 1.75)
			(layers "F.Cu" "F.Mask" "F.Paste")
			(net 377 "/Com Express 7 Interfaces/USB1.D-")
			(pinfunction "USB1-")
			(pintype "bidirectional")
			(teardrops
				(best_length_ratio 0.2)
				(max_length 1)
				(best_width_ratio 0.9)
				(max_width 2)
				(curved_edges yes)
				(filter_ratio 0.9)
				(enabled yes)
				(allow_two_segments yes)
				(prefer_zone_connections yes)
			)
		)
		(pad "B46" smd rect
			(at -4.75 3.325)
			(size 0.3 1.75)
			(layers "F.Cu" "F.Mask" "F.Paste")
			(net 378 "/Com Express 7 Interfaces/USB1.D+")
			(pinfunction "USB1+")
			(pintype "bidirectional")
			(teardrops
				(best_length_ratio 0.2)
				(max_length 1)
				(best_width_ratio 0.9)
				(max_width 2)
				(curved_edges yes)
				(filter_ratio 0.9)
				(enabled yes)
				(allow_two_segments yes)
				(prefer_zone_connections yes)
			)
		)
		(pad "B47" smd rect
			(at -4.25 3.325)
			(size 0.3 1.75)
			(layers "F.Cu" "F.Mask" "F.Paste")
			(net 379 "Net-(J12D-~{ESPI_EN})")
			(pinfunction "~{ESPI_EN}")
			(pintype "input")
			(teardrops
				(best_length_ratio 0.2)
				(max_length 1)
				(best_width_ratio 0.9)
				(max_width 2)
				(curved_edges yes)
				(filter_ratio 0.9)
				(enabled yes)
				(allow_two_segments yes)
				(prefer_zone_connections yes)
			)
		)
		(pad "B48" smd rect
			(at -3.75 3.325)
			(size 0.3 1.75)
			(layers "F.Cu" "F.Mask" "F.Paste")
			(net 380 "Net-(J12G-USB0_HOST_PRSNT)")
			(pinfunction "USB0_HOST_PRSNT")
			(pintype "input")
			(teardrops
				(best_length_ratio 0.2)
				(max_length 1)
				(best_width_ratio 0.9)
				(max_width 2)
				(curved_edges yes)
				(filter_ratio 0.9)
				(enabled yes)
				(allow_two_segments yes)
				(prefer_zone_connections yes)
			)
		)
		(pad "B49" smd rect
			(at -3.25 3.325)
			(size 0.3 1.75)
			(layers "F.Cu" "F.Mask" "F.Paste")
			(net 381 "Net-(J12D-~{SYS_RESET})")
			(pinfunction "~{SYS_RESET}")
			(pintype "input")
			(teardrops
				(best_length_ratio 0.2)
				(max_length 1)
				(best_width_ratio 0.9)
				(max_width 2)
				(curved_edges yes)
				(filter_ratio 0.9)
				(enabled yes)
				(allow_two_segments yes)
				(prefer_zone_connections yes)
			)
		)
	)
)
